(kicad_pcb
	(version 20260206)
	(generator "pcbnew")
	(generator_version "10.0")
	(general
		(thickness 1.6)
		(legacy_teardrops no)
	)
	(paper "A4")
	(title_block
		(title "04192023_DAF0TMB3IC0_F0TG_MB_C_brd_V02_OCP.brd")
		(comment 1 "Grand Teton / footprints 7102-7108 of 8354")
	)
	(layers
		(0 "F.Cu" signal "TOP")
		(4 "In1.Cu" signal "GND")
		(6 "In2.Cu" signal "IN1")
		(8 "In3.Cu" signal "GND1")
		(10 "In4.Cu" signal "IN2")
		(12 "In5.Cu" signal "GND2")
		(14 "In6.Cu" signal "IN3")
		(16 "In7.Cu" signal "GND3")
		(18 "In8.Cu" signal "VCC")
		(20 "In9.Cu" signal "VCC1")
		(22 "In10.Cu" signal "GND4")
		(24 "In11.Cu" signal "IN4")
		(26 "In12.Cu" signal "GND5")
		(28 "In13.Cu" signal "IN5")
		(30 "In14.Cu" signal "GND6")
		(32 "In15.Cu" signal "IN6")
		(34 "In16.Cu" signal "GND7")
		(2 "B.Cu" signal "BOTTOM")
		(9 "F.Adhes" user "F.Adhesive")
		(11 "B.Adhes" user "B.Adhesive")
		(13 "F.Paste" user "Package Geometry/Pastemask Top")
		(15 "B.Paste" user "Package Geometry/Pastemask Bottom")
		(5 "F.SilkS" user "Ref Des/Silkscreen Top")
		(7 "B.SilkS" user "Ref Des/Silkscreen Bottom")
		(1 "F.Mask" user "Board Geometry/Soldermask Top")
		(3 "B.Mask" user "Board Geometry/Soldermask Bottom")
		(17 "Dwgs.User" user "User.Drawings")
		(19 "Cmts.User" user "User.Comments")
		(21 "Eco1.User" user "User.Eco1")
		(23 "Eco2.User" user "User.Eco2")
		(25 "Edge.Cuts" user "Board Geometry/Outline")
		(27 "Margin" user)
		(31 "F.CrtYd" user "Package Geometry/Place Bound Top")
		(29 "B.CrtYd" user "Package Geometry/Place Bound Bottom")
		(35 "F.Fab" user "Ref Des/Assembly Top")
		(33 "B.Fab" user "Ref Des/Assembly Bottom")
	)
	(footprint ""
		(layer "B.Cu")
		(at 398.040606 -397.228568)
		(property "Reference" "C802"
			(at 0 0 0)
			(layer "B.SilkS")
			(hide yes)
			(effects
				(font
					(size 1.27 1.27)
				)
				(justify mirror)
			)
		)
		(property "Value" ""
			(at 0 0 0)
			(layer "B.Fab")
			(effects
				(font
					(size 1.27 1.27)
				)
				(justify mirror)
			)
		)
		(duplicate_pad_numbers_are_jumpers no)
		(fp_line
			(start -1.524 -0.762)
			(end -1.524 0.762)
			(stroke
				(width 0.1524)
				(type default)
			)
			(layer "B.SilkS")
		)
		(fp_line
			(start -1.524 0.762)
			(end 1.524 0.762)
			(stroke
				(width 0.1524)
				(type default)
			)
			(layer "B.SilkS")
		)
		(fp_line
			(start 1.524 -0.762)
			(end -1.524 -0.762)
			(stroke
				(width 0.1524)
				(type default)
			)
			(layer "B.SilkS")
		)
		(fp_line
			(start 1.524 0.762)
			(end 1.524 -0.762)
			(stroke
				(width 0.1524)
				(type default)
			)
			(layer "B.SilkS")
		)
		(fp_line
			(start -1.1049 -0.724916)
			(end 1.1049 -0.724916)
			(stroke
				(width 0.1)
				(type default)
			)
			(layer "B.Fab")
		)
		(fp_line
			(start -1.1049 0.724916)
			(end -1.1049 -0.724916)
			(stroke
				(width 0.1)
				(type default)
			)
			(layer "B.Fab")
		)
		(fp_line
			(start 1.1049 -0.724916)
			(end 1.1049 0.724916)
			(stroke
				(width 0.1)
				(type default)
			)
			(layer "B.Fab")
		)
		(fp_line
			(start 1.1049 0.724916)
			(end -1.1049 0.724916)
			(stroke
				(width 0.1)
				(type default)
			)
			(layer "B.Fab")
		)
		(pad "1" smd rect
			(at 0.889 0)
			(size 1.016 1.27)
			(layers "B.Cu" "B.Mask" "B.Paste")
			(net "P0V9_CPU0_RT2_2A")
		)
		(pad "2" smd rect
			(at -0.889 0)
			(size 1.016 1.27)
			(layers "B.Cu" "B.Mask" "B.Paste")
			(net "GND")
		)
	)
	(footprint ""
		(layer "B.Cu")
		(at 375.604786 -214.523828 90)
		(property "Reference" "R8566"
			(at 0 0 90)
			(layer "B.SilkS")
			(hide yes)
			(effects
				(font
					(size 1.27 1.27)
				)
				(justify mirror)
			)
		)
		(property "Value" ""
			(at 0 0 90)
			(layer "B.Fab")
			(effects
				(font
					(size 1.27 1.27)
				)
				(justify mirror)
			)
		)
		(duplicate_pad_numbers_are_jumpers no)
		(fp_line
			(start 0.7874 -0.4064)
			(end -0.7874 -0.4064)
			(stroke
				(width 0.1524)
				(type default)
			)
			(layer "B.SilkS")
		)
		(fp_line
			(start -0.7874 -0.4064)
			(end -0.7874 0.010414)
			(stroke
				(width 0.1524)
				(type default)
			)
			(layer "B.SilkS")
		)
		(fp_line
			(start 0.7874 -0.014986)
			(end 0.7874 -0.4064)
			(stroke
				(width 0.1524)
				(type default)
			)
			(layer "B.SilkS")
		)
		(fp_line
			(start -0.351028 0.4064)
			(end 0.385572 0.4064)
			(stroke
				(width 0.1524)
				(type default)
			)
			(layer "B.SilkS")
		)
		(fp_line
			(start 0.67945 -0.305054)
			(end 0.12065 -0.305054)
			(stroke
				(width 0.1)
				(type default)
			)
			(layer "B.Fab")
		)
		(fp_line
			(start 0.12065 -0.305054)
			(end 0.12065 -0.2794)
			(stroke
				(width 0.1)
				(type default)
			)
			(layer "B.Fab")
		)
		(fp_line
			(start -0.12065 -0.3048)
			(end -0.67945 -0.3048)
			(stroke
				(width 0.1)
				(type default)
			)
			(layer "B.Fab")
		)
		(fp_line
			(start -0.67945 -0.3048)
			(end -0.67945 0.3048)
			(stroke
				(width 0.1)
				(type default)
			)
			(layer "B.Fab")
		)
		(fp_line
			(start 0.12065 -0.2794)
			(end -0.12065 -0.2794)
			(stroke
				(width 0.1)
				(type default)
			)
			(layer "B.Fab")
		)
		(fp_line
			(start -0.12065 -0.2794)
			(end -0.12065 -0.3048)
			(stroke
				(width 0.1)
				(type default)
			)
			(layer "B.Fab")
		)
		(fp_line
			(start 0.12065 0.2794)
			(end 0.12065 0.3048)
			(stroke
				(width 0.1)
				(type default)
			)
			(layer "B.Fab")
		)
		(fp_line
			(start -0.120396 0.2794)
			(end 0.12065 0.2794)
			(stroke
				(width 0.1)
				(type default)
			)
			(layer "B.Fab")
		)
		(fp_line
			(start 0.67945 0.3048)
			(end 0.67945 -0.305054)
			(stroke
				(width 0.1)
				(type default)
			)
			(layer "B.Fab")
		)
		(fp_line
			(start 0.12065 0.3048)
			(end 0.67945 0.3048)
			(stroke
				(width 0.1)
				(type default)
			)
			(layer "B.Fab")
		)
		(fp_line
			(start -0.120396 0.3048)
			(end -0.120396 0.2794)
			(stroke
				(width 0.1)
				(type default)
			)
			(layer "B.Fab")
		)
		(fp_line
			(start -0.67945 0.3048)
			(end -0.120396 0.3048)
			(stroke
				(width 0.1)
				(type default)
			)
			(layer "B.Fab")
		)
		(pad "1" smd circle
			(at 0.40005 0 270)
			(size 0 0)
			(layers "B.Cu" "B.Mask" "B.Paste")
			(net "CLK_100M_CPU0_CLK03_R_DN")
		)
		(pad "2" smd circle
			(at -0.40005 0 270)
			(size 0 0)
			(layers "B.Cu" "B.Mask" "B.Paste")
			(net "CLK_100M_CPU0_CLK03_DN")
		)
	)
	(footprint ""
		(layer "B.Cu")
		(at 197.269608 -119.721376 180)
		(property "Reference" "R4558"
			(at 0 0 0)
			(layer "B.SilkS")
			(hide yes)
			(effects
				(font
					(size 1.27 1.27)
				)
				(justify mirror)
			)
		)
		(property "Value" ""
			(at 0 0 0)
			(layer "B.Fab")
			(effects
				(font
					(size 1.27 1.27)
				)
				(justify mirror)
			)
		)
		(duplicate_pad_numbers_are_jumpers no)
		(fp_line
			(start 0.7874 0.4064)
			(end 0.7874 -0.4064)
			(stroke
				(width 0.1524)
				(type default)
			)
			(layer "B.SilkS")
		)
		(fp_line
			(start 0.7874 -0.4064)
			(end -0.7874 -0.4064)
			(stroke
				(width 0.1524)
				(type default)
			)
			(layer "B.SilkS")
		)
		(fp_line
			(start -0.7874 0.4064)
			(end 0.7874 0.4064)
			(stroke
				(width 0.1524)
				(type default)
			)
			(layer "B.SilkS")
		)
		(fp_line
			(start -0.7874 -0.4064)
			(end -0.7874 0.4064)
			(stroke
				(width 0.1524)
				(type default)
			)
			(layer "B.SilkS")
		)
		(fp_line
			(start 0.67945 0.3048)
			(end 0.67945 -0.305054)
			(stroke
				(width 0.1)
				(type default)
			)
			(layer "B.Fab")
		)
		(fp_line
			(start 0.67945 -0.305054)
			(end 0.12065 -0.305054)
			(stroke
				(width 0.1)
				(type default)
			)
			(layer "B.Fab")
		)
		(fp_line
			(start 0.12065 0.3048)
			(end 0.67945 0.3048)
			(stroke
				(width 0.1)
				(type default)
			)
			(layer "B.Fab")
		)
		(fp_line
			(start 0.12065 0.2794)
			(end 0.12065 0.3048)
			(stroke
				(width 0.1)
				(type default)
			)
			(layer "B.Fab")
		)
		(fp_line
			(start 0.12065 -0.2794)
			(end -0.12065 -0.2794)
			(stroke
				(width 0.1)
				(type default)
			)
			(layer "B.Fab")
		)
		(fp_line
			(start 0.12065 -0.305054)
			(end 0.12065 -0.2794)
			(stroke
				(width 0.1)
				(type default)
			)
			(layer "B.Fab")
		)
		(fp_line
			(start -0.120396 0.3048)
			(end -0.120396 0.2794)
			(stroke
				(width 0.1)
				(type default)
			)
			(layer "B.Fab")
		)
		(fp_line
			(start -0.120396 0.2794)
			(end 0.12065 0.2794)
			(stroke
				(width 0.1)
				(type default)
			)
			(layer "B.Fab")
		)
		(fp_line
			(start -0.12065 -0.2794)
			(end -0.12065 -0.3048)
			(stroke
				(width 0.1)
				(type default)
			)
			(layer "B.Fab")
		)
		(fp_line
			(start -0.12065 -0.3048)
			(end -0.67945 -0.3048)
			(stroke
				(width 0.1)
				(type default)
			)
			(layer "B.Fab")
		)
		(fp_line
			(start -0.67945 0.3048)
			(end -0.120396 0.3048)
			(stroke
				(width 0.1)
				(type default)
			)
			(layer "B.Fab")
		)
		(fp_line
			(start -0.67945 -0.3048)
			(end -0.67945 0.3048)
			(stroke
				(width 0.1)
				(type default)
			)
			(layer "B.Fab")
		)
		(pad "1" smd circle
			(at 0.40005 0)
			(size 0 0)
			(layers "B.Cu" "B.Mask" "B.Paste")
			(net "SWB_HSC_EN_R")
		)
		(pad "2" smd circle
			(at -0.40005 0)
			(size 0 0)
			(layers "B.Cu" "B.Mask" "B.Paste")
			(net "SWB_HSC_EN")
		)
	)
	(footprint ""
		(layer "B.Cu")
		(at 383.655316 -191.334898 90)
		(property "Reference" "PC562_3"
			(at 0 0 90)
			(layer "B.SilkS")
			(hide yes)
			(effects
				(font
					(size 1.27 1.27)
				)
				(justify mirror)
			)
		)
		(property "Value" ""
			(at 0 0 90)
			(layer "B.Fab")
			(effects
				(font
					(size 1.27 1.27)
				)
				(justify mirror)
			)
		)
		(duplicate_pad_numbers_are_jumpers no)
		(fp_line
			(start 1.524 -0.762)
			(end -1.524 -0.762)
			(stroke
				(width 0.1524)
				(type default)
			)
			(layer "B.SilkS")
		)
		(fp_line
			(start -1.524 -0.762)
			(end -1.524 0.762)
			(stroke
				(width 0.1524)
				(type default)
			)
			(layer "B.SilkS")
		)
		(fp_line
			(start 1.524 0.762)
			(end 1.524 -0.762)
			(stroke
				(width 0.1524)
				(type default)
			)
			(layer "B.SilkS")
		)
		(fp_line
			(start -1.524 0.762)
			(end 1.524 0.762)
			(stroke
				(width 0.1524)
				(type default)
			)
			(layer "B.SilkS")
		)
		(fp_line
			(start 1.1049 -0.724916)
			(end 1.1049 0.724916)
			(stroke
				(width 0.1)
				(type default)
			)
			(layer "B.Fab")
		)
		(fp_line
			(start -1.1049 -0.724916)
			(end 1.1049 -0.724916)
			(stroke
				(width 0.1)
				(type default)
			)
			(layer "B.Fab")
		)
		(fp_line
			(start 1.1049 0.724916)
			(end -1.1049 0.724916)
			(stroke
				(width 0.1)
				(type default)
			)
			(layer "B.Fab")
		)
		(fp_line
			(start -1.1049 0.724916)
			(end -1.1049 -0.724916)
			(stroke
				(width 0.1)
				(type default)
			)
			(layer "B.Fab")
		)
		(pad "1" smd rect
			(at 0.889 0 90)
			(size 1.016 1.27)
			(layers "B.Cu" "B.Mask" "B.Paste")
			(net "PVDDCR_CPU0_P0")
		)
		(pad "2" smd rect
			(at -0.889 0 90)
			(size 1.016 1.27)
			(layers "B.Cu" "B.Mask" "B.Paste")
			(net "GND")
		)
	)
	(footprint ""
		(layer "B.Cu")
		(at 87.432134 -182.607966 -90)
		(property "Reference" "PC269_2"
			(at 0 0 90)
			(layer "B.SilkS")
			(hide yes)
			(effects
				(font
					(size 1.27 1.27)
				)
				(justify mirror)
			)
		)
		(property "Value" ""
			(at 0 0 90)
			(layer "B.Fab")
			(effects
				(font
					(size 1.27 1.27)
				)
				(justify mirror)
			)
		)
		(duplicate_pad_numbers_are_jumpers no)
		(fp_line
			(start -1.524 0.762)
			(end 1.524 0.762)
			(stroke
				(width 0.1524)
				(type default)
			)
			(layer "B.SilkS")
		)
		(fp_line
			(start 1.524 0.762)
			(end 1.524 -0.762)
			(stroke
				(width 0.1524)
				(type default)
			)
			(layer "B.SilkS")
		)
		(fp_line
			(start -1.524 -0.762)
			(end -1.524 0.762)
			(stroke
				(width 0.1524)
				(type default)
			)
			(layer "B.SilkS")
		)
		(fp_line
			(start 1.524 -0.762)
			(end -1.524 -0.762)
			(stroke
				(width 0.1524)
				(type default)
			)
			(layer "B.SilkS")
		)
		(fp_line
			(start -1.1049 0.724916)
			(end -1.1049 -0.724916)
			(stroke
				(width 0.1)
				(type default)
			)
			(layer "B.Fab")
		)
		(fp_line
			(start 1.1049 0.724916)
			(end -1.1049 0.724916)
			(stroke
				(width 0.1)
				(type default)
			)
			(layer "B.Fab")
		)
		(fp_line
			(start -1.1049 -0.724916)
			(end 1.1049 -0.724916)
			(stroke
				(width 0.1)
				(type default)
			)
			(layer "B.Fab")
		)
		(fp_line
			(start 1.1049 -0.724916)
			(end 1.1049 0.724916)
			(stroke
				(width 0.1)
				(type default)
			)
			(layer "B.Fab")
		)
		(pad "1" smd rect
			(at 0.889 0 270)
			(size 1.016 1.27)
			(layers "B.Cu" "B.Mask" "B.Paste")
			(net "SW_P12V_AUX_PVDDCR_CPU0_P1_FLT")
		)
		(pad "2" smd rect
			(at -0.889 0 270)
			(size 1.016 1.27)
			(layers "B.Cu" "B.Mask" "B.Paste")
			(net "GND")
		)
	)
	(footprint ""
		(layer "B.Cu")
		(at 179.162964 -425.394882 90)
		(property "Reference" "U142"
			(at 3.405632 2.674874 0)
			(unlocked yes)
			(layer "B.SilkS")
			(effects
				(font
					(size 0.7874 0.5842)
					(thickness 0.1524)
				)
				(justify left mirror)
			)
		)
		(property "Value" ""
			(at 0 0 90)
			(layer "B.Fab")
			(effects
				(font
					(size 1.27 1.27)
				)
				(justify mirror)
			)
		)
		(duplicate_pad_numbers_are_jumpers no)
		(fp_line
			(start 2.046478 -1.450086)
			(end 2.046478 1.450086)
			(stroke
				(width 0.1524)
				(type default)
			)
			(layer "B.SilkS")
		)
		(fp_line
			(start 0.484886 -1.450086)
			(end 2.046478 -1.450086)
			(stroke
				(width 0.1524)
				(type default)
			)
			(layer "B.SilkS")
		)
		(fp_line
			(start -0.484886 -1.450086)
			(end 0 -0.762)
			(stroke
				(width 0.1524)
				(type default)
			)
			(layer "B.SilkS")
		)
		(fp_line
			(start -2.046478 -1.450086)
			(end -0.484886 -1.450086)
			(stroke
				(width 0.1524)
				(type default)
			)
			(layer "B.SilkS")
		)
		(fp_line
			(start 0 -0.762)
			(end 0.484886 -1.450086)
			(stroke
				(width 0.1524)
				(type default)
			)
			(layer "B.SilkS")
		)
		(fp_line
			(start 2.046478 1.450086)
			(end -2.046478 1.450086)
			(stroke
				(width 0.1524)
				(type default)
			)
			(layer "B.SilkS")
		)
		(fp_line
			(start -2.046478 1.450086)
			(end -2.046478 -1.450086)
			(stroke
				(width 0.1524)
				(type default)
			)
			(layer "B.SilkS")
		)
		(fp_poly
			(pts
				(xy 2.2352 -0.94996) (xy 3.2512 -0.44196) (xy 3.2512 -1.45796)
			)
			(stroke
				(width 0)
				(type default)
			)
			(fill yes)
			(layer "B.SilkS")
		)
		(fp_line
			(start 0.87503 -1.450086)
			(end 0.87503 1.450086)
			(stroke
				(width 0.1)
				(type default)
			)
			(layer "B.Fab")
		)
		(fp_line
			(start -0.87503 -1.450086)
			(end 0.87503 -1.450086)
			(stroke
				(width 0.1)
				(type default)
			)
			(layer "B.Fab")
		)
		(fp_line
			(start 0.87503 1.450086)
			(end -0.87503 1.450086)
			(stroke
				(width 0.1)
				(type default)
			)
			(layer "B.Fab")
		)
		(fp_line
			(start -0.87503 1.450086)
			(end -0.87503 -1.450086)
			(stroke
				(width 0.1)
				(type default)
			)
			(layer "B.Fab")
		)
		(fp_poly
			(pts
				(xy 3.2512 -0.44196) (xy 3.2512 -1.45796) (xy 2.2352 -0.94996)
			)
			(stroke
				(width 0)
				(type default)
			)
			(fill yes)
			(layer "B.Fab")
		)
		(pad "1" smd rect
			(at 1.309878 -0.94996 180)
			(size 0.635 1.2192)
			(layers "B.Cu" "B.Mask" "B.Paste")
			(net "A_HSC_LOW_GATE")
		)
		(pad "2" smd rect
			(at 1.309878 0 180)
			(size 0.635 1.2192)
			(layers "B.Cu" "B.Mask" "B.Paste")
			(net "GND")
		)
		(pad "3" smd rect
			(at 1.309878 0.94996 180)
			(size 0.635 1.2192)
			(layers "B.Cu" "B.Mask" "B.Paste")
			(net "A_HSC_LOW")
		)
		(pad "4" smd rect
			(at -1.309878 0.94996 180)
			(size 0.635 1.2192)
			(layers "B.Cu" "B.Mask" "B.Paste")
			(net "A_HSC_HIGH")
		)
		(pad "5" smd rect
			(at -1.309878 0 180)
			(size 0.635 1.2192)
			(layers "B.Cu" "B.Mask" "B.Paste")
			(net "U142_VS")
		)
		(pad "6" smd rect
			(at -1.309878 -0.94996 180)
			(size 0.635 1.2192)
			(layers "B.Cu" "B.Mask" "B.Paste")
			(net "HSC_D_OC")
		)
	)
	(footprint ""
		(layer "B.Cu")
		(at 29.722318 -350.660716 -90)
		(property "Reference" "PC629_4"
			(at 0 0 90)
			(layer "B.SilkS")
			(hide yes)
			(effects
				(font
					(size 1.27 1.27)
				)
				(justify mirror)
			)
		)
		(property "Value" ""
			(at 0 0 90)
			(layer "B.Fab")
			(effects
				(font
					(size 1.27 1.27)
				)
				(justify mirror)
			)
		)
		(duplicate_pad_numbers_are_jumpers no)
		(fp_line
			(start -1.524 0.762)
			(end 1.524 0.762)
			(stroke
				(width 0.1524)
				(type default)
			)
			(layer "B.SilkS")
		)
		(fp_line
			(start 1.524 0.762)
			(end 1.524 -0.762)
			(stroke
				(width 0.1524)
				(type default)
			)
			(layer "B.SilkS")
		)
		(fp_line
			(start -1.524 -0.762)
			(end -1.524 0.762)
			(stroke
				(width 0.1524)
				(type default)
			)
			(layer "B.SilkS")
		)
		(fp_line
			(start 1.524 -0.762)
			(end -1.524 -0.762)
			(stroke
				(width 0.1524)
				(type default)
			)
			(layer "B.SilkS")
		)
		(fp_line
			(start -1.1049 0.724916)
			(end -1.1049 -0.724916)
			(stroke
				(width 0.1)
				(type default)
			)
			(layer "B.Fab")
		)
		(fp_line
			(start 1.1049 0.724916)
			(end -1.1049 0.724916)
			(stroke
				(width 0.1)
				(type default)
			)
			(layer "B.Fab")
		)
		(fp_line
			(start -1.1049 -0.724916)
			(end 1.1049 -0.724916)
			(stroke
				(width 0.1)
				(type default)
			)
			(layer "B.Fab")
		)
		(fp_line
			(start 1.1049 -0.724916)
			(end 1.1049 0.724916)
			(stroke
				(width 0.1)
				(type default)
			)
			(layer "B.Fab")
		)
		(pad "1" smd rect
			(at 0.889 0 270)
			(size 1.016 1.27)
			(layers "B.Cu" "B.Mask" "B.Paste")
			(net "SW_P12V_AUX_PVDDIO_P1_FLT")
		)
		(pad "2" smd rect
			(at -0.889 0 270)
			(size 1.016 1.27)
			(layers "B.Cu" "B.Mask" "B.Paste")
			(net "GND")
		)
	)
)
